# S9S_MB_2U (Grand Teton) — schematic netlist excerpt (pin names and nets, part order shuffled) for the footprints in the layout excerpt that follows; sources: Cadence DE-HDL packaged netlist, KiCad conversion of 03242023_DA0F0TMBIJ0_F0T_Motherboard_J_brd_V01_OCP.brd

C2071  Q_CAP  0.1UF 25V 10% X7R  pkg 0402  page 171 : A = VSENSE_P3V3_INA230_2_INP ; B = VSENSE_P3V3_INA230_2_INN
PC559_P1_1  Q_CAP  2.2UF 10V 10% X6S  pkg C0402  page 285 : A = PVCCIN_CPU1_PVCC ; B = GND

(kicad_pcb
	(version 20260206)
	(generator "pcbnew")
	(generator_version "10.0")
	(general
		(thickness 1.6)
		(legacy_teardrops no)
	)
	(paper "A4")
	(title_block
		(title "03242023_DA0F0TMBIJ0_F0T_Motherboard_J_brd_V01_OCP.brd")
		(comment 1 "Grand Teton / footprints 1544-1545 of 6105")
	)
	(layers
		(0 "F.Cu" signal "TOP")
		(4 "In1.Cu" signal "GND")
		(6 "In2.Cu" signal "IN1")
		(8 "In3.Cu" signal "GND1")
		(10 "In4.Cu" signal "IN2")
		(12 "In5.Cu" signal "GND2")
		(14 "In6.Cu" signal "IN3")
		(16 "In7.Cu" signal "GND3")
		(18 "In8.Cu" signal "VCC")
		(20 "In9.Cu" signal "VCC1")
		(22 "In10.Cu" signal "GND4")
		(24 "In11.Cu" signal "IN4")
		(26 "In12.Cu" signal "GND5")
		(28 "In13.Cu" signal "IN5")
		(30 "In14.Cu" signal "GND6")
		(32 "In15.Cu" signal "IN6")
		(34 "In16.Cu" signal "GND7")
		(2 "B.Cu" signal "BOTTOM")
		(9 "F.Adhes" user "F.Adhesive")
		(11 "B.Adhes" user "B.Adhesive")
		(13 "F.Paste" user "Package Geometry/Pastemask Top")
		(15 "B.Paste" user "Package Geometry/Pastemask Bottom")
		(5 "F.SilkS" user "Ref Des/Silkscreen Top")
		(7 "B.SilkS" user "Ref Des/Silkscreen Bottom")
		(1 "F.Mask" user "Board Geometry/Soldermask Top")
		(3 "B.Mask" user "Board Geometry/Soldermask Bottom")
		(17 "Dwgs.User" user "User.Drawings")
		(19 "Cmts.User" user "User.Comments")
		(21 "Eco1.User" user "User.Eco1")
		(23 "Eco2.User" user "User.Eco2")
		(25 "Edge.Cuts" user "Board Geometry/Outline")
		(27 "Margin" user)
		(31 "F.CrtYd" user "Package Geometry/Place Bound Top")
		(29 "B.CrtYd" user "Package Geometry/Place Bound Bottom")
		(35 "F.Fab" user "Ref Des/Assembly Top")
		(33 "B.Fab" user "Ref Des/Assembly Bottom")
	)
	(footprint ""
		(layer "F.Cu")
		(at 218.130882 -57.399682 -90)
		(property "Reference" "C2071"
			(at 0 0 270)
			(layer "F.SilkS")
			(hide yes)
			(effects
				(font
					(size 1.27 1.27)
				)
			)
		)
		(property "Value" ""
			(at 0 0 270)
			(layer "F.Fab")
			(effects
				(font
					(size 1.27 1.27)
				)
			)
		)
		(duplicate_pad_numbers_are_jumpers no)
		(fp_line
			(start -0.7874 0.4064)
			(end -0.7874 -0.4064)
			(stroke
				(width 0.1524)
				(type default)
			)
			(layer "F.SilkS")
		)
		(fp_line
			(start 0.7874 0.4064)
			(end -0.7874 0.4064)
			(stroke
				(width 0.1524)
				(type default)
			)
			(layer "F.SilkS")
		)
		(fp_line
			(start -0.7874 -0.4064)
			(end 0.7874 -0.4064)
			(stroke
				(width 0.1524)
				(type default)
			)
			(layer "F.SilkS")
		)
		(fp_line
			(start 0.7874 -0.4064)
			(end 0.7874 0.4064)
			(stroke
				(width 0.1524)
				(type default)
			)
			(layer "F.SilkS")
		)
		(fp_line
			(start -0.67945 0.3048)
			(end -0.67945 -0.305054)
			(stroke
				(width 0.1)
				(type default)
			)
			(layer "F.Fab")
		)
		(fp_line
			(start -0.12065 0.3048)
			(end -0.67945 0.3048)
			(stroke
				(width 0.1)
				(type default)
			)
			(layer "F.Fab")
		)
		(fp_line
			(start 0.120396 0.3048)
			(end 0.120396 0.2794)
			(stroke
				(width 0.1)
				(type default)
			)
			(layer "F.Fab")
		)
		(fp_line
			(start 0.67945 0.3048)
			(end 0.120396 0.3048)
			(stroke
				(width 0.1)
				(type default)
			)
			(layer "F.Fab")
		)
		(fp_line
			(start -0.12065 0.2794)
			(end -0.12065 0.3048)
			(stroke
				(width 0.1)
				(type default)
			)
			(layer "F.Fab")
		)
		(fp_line
			(start 0.120396 0.2794)
			(end -0.12065 0.2794)
			(stroke
				(width 0.1)
				(type default)
			)
			(layer "F.Fab")
		)
		(fp_line
			(start -0.12065 -0.2794)
			(end 0.12065 -0.2794)
			(stroke
				(width 0.1)
				(type default)
			)
			(layer "F.Fab")
		)
		(fp_line
			(start 0.12065 -0.2794)
			(end 0.12065 -0.3048)
			(stroke
				(width 0.1)
				(type default)
			)
			(layer "F.Fab")
		)
		(fp_line
			(start 0.12065 -0.3048)
			(end 0.67945 -0.3048)
			(stroke
				(width 0.1)
				(type default)
			)
			(layer "F.Fab")
		)
		(fp_line
			(start 0.67945 -0.3048)
			(end 0.67945 0.3048)
			(stroke
				(width 0.1)
				(type default)
			)
			(layer "F.Fab")
		)
		(fp_line
			(start -0.67945 -0.305054)
			(end -0.12065 -0.305054)
			(stroke
				(width 0.1)
				(type default)
			)
			(layer "F.Fab")
		)
		(fp_line
			(start -0.12065 -0.305054)
			(end -0.12065 -0.2794)
			(stroke
				(width 0.1)
				(type default)
			)
			(layer "F.Fab")
		)
		(pad "1" smd circle
			(at -0.40005 0 270)
			(size 0 0)
			(layers "F.Cu" "F.Mask" "F.Paste")
			(net "VSENSE_P3V3_INA230_2_INP")
		)
		(pad "2" smd circle
			(at 0.40005 0 270)
			(size 0 0)
			(layers "F.Cu" "F.Mask" "F.Paste")
			(net "VSENSE_P3V3_INA230_2_INN")
		)
	)
	(footprint ""
		(layer "F.Cu")
		(at 93.400118 -333.525368 -90)
		(property "Reference" "PC559_P1_1"
			(at 0 0 270)
			(layer "F.SilkS")
			(hide yes)
			(effects
				(font
					(size 1.27 1.27)
				)
			)
		)
		(property "Value" ""
			(at 0 0 270)
			(layer "F.Fab")
			(effects
				(font
					(size 1.27 1.27)
				)
			)
		)
		(duplicate_pad_numbers_are_jumpers no)
		(fp_line
			(start -0.7874 0.4064)
			(end -0.7874 -0.4064)
			(stroke
				(width 0.1524)
				(type default)
			)
			(layer "F.SilkS")
		)
		(fp_line
			(start 0.7874 0.4064)
			(end -0.7874 0.4064)
			(stroke
				(width 0.1524)
				(type default)
			)
			(layer "F.SilkS")
		)
		(fp_line
			(start -0.7874 -0.4064)
			(end 0.7874 -0.4064)
			(stroke
				(width 0.1524)
				(type default)
			)
			(layer "F.SilkS")
		)
		(fp_line
			(start 0.7874 -0.4064)
			(end 0.7874 0.4064)
			(stroke
				(width 0.1524)
				(type default)
			)
			(layer "F.SilkS")
		)
		(fp_line
			(start -0.67945 0.3048)
			(end -0.67945 -0.305054)
			(stroke
				(width 0.1)
				(type default)
			)
			(layer "F.Fab")
		)
		(fp_line
			(start -0.12065 0.3048)
			(end -0.67945 0.3048)
			(stroke
				(width 0.1)
				(type default)
			)
			(layer "F.Fab")
		)
		(fp_line
			(start 0.120396 0.3048)
			(end 0.120396 0.2794)
			(stroke
				(width 0.1)
				(type default)
			)
			(layer "F.Fab")
		)
		(fp_line
			(start 0.67945 0.3048)
			(end 0.120396 0.3048)
			(stroke
				(width 0.1)
				(type default)
			)
			(layer "F.Fab")
		)
		(fp_line
			(start -0.12065 0.2794)
			(end -0.12065 0.3048)
			(stroke
				(width 0.1)
				(type default)
			)
			(layer "F.Fab")
		)
		(fp_line
			(start 0.120396 0.2794)
			(end -0.12065 0.2794)
			(stroke
				(width 0.1)
				(type default)
			)
			(layer "F.Fab")
		)
		(fp_line
			(start -0.12065 -0.2794)
			(end 0.12065 -0.2794)
			(stroke
				(width 0.1)
				(type default)
			)
			(layer "F.Fab")
		)
		(fp_line
			(start 0.12065 -0.2794)
			(end 0.12065 -0.3048)
			(stroke
				(width 0.1)
				(type default)
			)
			(layer "F.Fab")
		)
		(fp_line
			(start 0.12065 -0.3048)
			(end 0.67945 -0.3048)
			(stroke
				(width 0.1)
				(type default)
			)
			(layer "F.Fab")
		)
		(fp_line
			(start 0.67945 -0.3048)
			(end 0.67945 0.3048)
			(stroke
				(width 0.1)
				(type default)
			)
			(layer "F.Fab")
		)
		(fp_line
			(start -0.67945 -0.305054)
			(end -0.12065 -0.305054)
			(stroke
				(width 0.1)
				(type default)
			)
			(layer "F.Fab")
		)
		(fp_line
			(start -0.12065 -0.305054)
			(end -0.12065 -0.2794)
			(stroke
				(width 0.1)
				(type default)
			)
			(layer "F.Fab")
		)
		(pad "1" smd circle
			(at -0.40005 0 270)
			(size 0 0)
			(layers "F.Cu" "F.Mask" "F.Paste")
			(net "PVCCIN_CPU1_PVCC")
		)
		(pad "2" smd circle
			(at 0.40005 0 270)
			(size 0 0)
			(layers "F.Cu" "F.Mask" "F.Paste")
			(net "GND")
		)
	)
)
